(kicad_pcb
	(version 20260206)
	(generator "pcbnew")
	(generator_version "10.0")
	(general
		(thickness 1.6)
		(legacy_teardrops no)
	)
	(paper "A4")
	(title_block
		(title "03242023_DA0F0TMBIJ0_F0T_Motherboard_J_brd_V01_OCP.brd")
		(comment 1 "Grand Teton / footprint 3039 of 6105 (U2), pads 534-640 of 4677")
	)
	(layers
		(0 "F.Cu" signal "TOP")
		(4 "In1.Cu" signal "GND")
		(6 "In2.Cu" signal "IN1")
		(8 "In3.Cu" signal "GND1")
		(10 "In4.Cu" signal "IN2")
		(12 "In5.Cu" signal "GND2")
		(14 "In6.Cu" signal "IN3")
		(16 "In7.Cu" signal "GND3")
		(18 "In8.Cu" signal "VCC")
		(20 "In9.Cu" signal "VCC1")
		(22 "In10.Cu" signal "GND4")
		(24 "In11.Cu" signal "IN4")
		(26 "In12.Cu" signal "GND5")
		(28 "In13.Cu" signal "IN5")
		(30 "In14.Cu" signal "GND6")
		(32 "In15.Cu" signal "IN6")
		(34 "In16.Cu" signal "GND7")
		(2 "B.Cu" signal "BOTTOM")
		(9 "F.Adhes" user "F.Adhesive")
		(11 "B.Adhes" user "B.Adhesive")
		(13 "F.Paste" user "Package Geometry/Pastemask Top")
		(15 "B.Paste" user "Package Geometry/Pastemask Bottom")
		(5 "F.SilkS" user "Ref Des/Silkscreen Top")
		(7 "B.SilkS" user "Ref Des/Silkscreen Bottom")
		(1 "F.Mask" user "Board Geometry/Soldermask Top")
		(3 "B.Mask" user "Board Geometry/Soldermask Bottom")
		(17 "Dwgs.User" user "User.Drawings")
		(19 "Cmts.User" user "User.Comments")
		(21 "Eco1.User" user "User.Eco1")
		(23 "Eco2.User" user "User.Eco2")
		(25 "Edge.Cuts" user "Board Geometry/Outline")
		(27 "Margin" user)
		(31 "F.CrtYd" user "Package Geometry/Place Bound Top")
		(29 "B.CrtYd" user "Package Geometry/Place Bound Bottom")
		(35 "F.Fab" user "Ref Des/Assembly Top")
		(33 "B.Fab" user "Ref Des/Assembly Bottom")
	)
	(footprint ""
		(layer "F.Cu")
		(at 359.870248 -251.76988 90)
		(property "Reference" "U2"
			(at -74.416158 -44.488608 0)
			(unlocked yes)
			(layer "F.SilkS")
			(effects
				(font
					(size 1.6002 1.1938)
					(thickness 0.1524)
				)
				(justify left)
			)
		)
		(property "Value" ""
			(at 0 0 90)
			(layer "F.Fab")
			(effects
				(font
					(size 1.27 1.27)
				)
			)
		)
		(duplicate_pad_numbers_are_jumpers no)
		(pad "AM26" smd circle
			(at -17.07769 -12.507468 270)
			(size 0.4318 0.4318)
			(layers "F.Cu" "F.Mask" "F.Paste")
			(net "GND")
		)
		(pad "AM28" smd circle
			(at -15.450058 -12.507468 270)
			(size 0.4318 0.4318)
			(layers "F.Cu" "F.Mask" "F.Paste")
			(net "GND")
		)
		(pad "AM30" smd circle
			(at -13.822426 -12.507468 270)
			(size 0.4318 0.4318)
			(layers "F.Cu" "F.Mask" "F.Paste")
			(net "GND")
		)
		(pad "AM32" smd circle
			(at -12.19454 -12.507468 270)
			(size 0.4318 0.4318)
			(layers "F.Cu" "F.Mask" "F.Paste")
			(net "GND")
		)
		(pad "AM34" smd circle
			(at -10.566654 -12.507468 270)
			(size 0.4318 0.4318)
			(layers "F.Cu" "F.Mask" "F.Paste")
			(net "GND")
		)
		(pad "AM36" smd circle
			(at -8.939022 -12.507468 270)
			(size 0.4318 0.4318)
			(layers "F.Cu" "F.Mask" "F.Paste")
			(net "GND")
		)
		(pad "AM38" smd circle
			(at -7.311136 -12.507468 270)
			(size 0.4318 0.4318)
			(layers "F.Cu" "F.Mask" "F.Paste")
			(net "GND")
		)
		(pad "AM40" smd circle
			(at -5.68325 -12.507468 270)
			(size 0.4318 0.4318)
			(layers "F.Cu" "F.Mask" "F.Paste")
			(net "GND")
		)
		(pad "AM42" smd circle
			(at -4.055618 -12.507468 270)
			(size 0.4318 0.4318)
			(layers "F.Cu" "F.Mask" "F.Paste")
			(net "GND")
		)
		(pad "AM44" smd circle
			(at -2.427732 -12.507468 270)
			(size 0.4318 0.4318)
			(layers "F.Cu" "F.Mask" "F.Paste")
			(net "GND")
		)
		(pad "AM47" smd circle
			(at 1.613916 -12.397486 270)
			(size 0.4318 0.4318)
			(layers "F.Cu" "F.Mask" "F.Paste")
			(net "GND")
		)
		(pad "AM49" smd circle
			(at 3.241802 -12.397486 270)
			(size 0.4318 0.4318)
			(layers "F.Cu" "F.Mask" "F.Paste")
			(net "GND")
		)
		(pad "AM51" smd circle
			(at 4.869434 -12.397486 270)
			(size 0.4318 0.4318)
			(layers "F.Cu" "F.Mask" "F.Paste")
			(net "GND")
		)
		(pad "AM53" smd circle
			(at 6.49732 -12.397486 270)
			(size 0.4318 0.4318)
			(layers "F.Cu" "F.Mask" "F.Paste")
			(net "GND")
		)
		(pad "AM55" smd circle
			(at 8.124952 -12.397486 270)
			(size 0.4318 0.4318)
			(layers "F.Cu" "F.Mask" "F.Paste")
			(net "GND")
		)
		(pad "AM57" smd circle
			(at 9.752838 -12.397486 270)
			(size 0.4318 0.4318)
			(layers "F.Cu" "F.Mask" "F.Paste")
			(net "GND")
		)
		(pad "AM59" smd circle
			(at 11.380724 -12.397486 270)
			(size 0.4318 0.4318)
			(layers "F.Cu" "F.Mask" "F.Paste")
			(net "GND")
		)
		(pad "AM61" smd circle
			(at 13.008356 -12.397486 270)
			(size 0.4318 0.4318)
			(layers "F.Cu" "F.Mask" "F.Paste")
			(net "GND")
		)
		(pad "AM63" smd circle
			(at 14.635988 -12.397486 270)
			(size 0.4318 0.4318)
			(layers "F.Cu" "F.Mask" "F.Paste")
			(net "GND")
		)
		(pad "AM65" smd circle
			(at 16.263874 -12.397486 270)
			(size 0.4318 0.4318)
			(layers "F.Cu" "F.Mask" "F.Paste")
			(net "GND")
		)
		(pad "AM67" smd circle
			(at 17.89176 -12.397486 270)
			(size 0.4318 0.4318)
			(layers "F.Cu" "F.Mask" "F.Paste")
			(net "GND")
		)
		(pad "AM69" smd circle
			(at 19.519392 -12.397486 270)
			(size 0.4318 0.4318)
			(layers "F.Cu" "F.Mask" "F.Paste")
			(net "GND")
		)
		(pad "AM71" smd circle
			(at 21.147278 -12.397486 270)
			(size 0.4318 0.4318)
			(layers "F.Cu" "F.Mask" "F.Paste")
			(net "GND")
		)
		(pad "AM73" smd circle
			(at 22.77491 -12.397486 270)
			(size 0.4318 0.4318)
			(layers "F.Cu" "F.Mask" "F.Paste")
			(net "GND")
		)
		(pad "AM75" smd circle
			(at 24.402796 -12.397486 270)
			(size 0.4318 0.4318)
			(layers "F.Cu" "F.Mask" "F.Paste")
			(net "GND")
		)
		(pad "AM77" smd circle
			(at 26.030682 -12.397486 270)
			(size 0.4318 0.4318)
			(layers "F.Cu" "F.Mask" "F.Paste")
			(net "GND")
		)
		(pad "AM79" smd circle
			(at 27.658314 -12.397486 270)
			(size 0.4318 0.4318)
			(layers "F.Cu" "F.Mask" "F.Paste")
			(net "PVCCFA_EHV_FIVRA_CPU0")
		)
		(pad "AM81" smd circle
			(at 29.2862 -12.397486 270)
			(size 0.4318 0.4318)
			(layers "F.Cu" "F.Mask" "F.Paste")
			(net "UPI_CPU0_CPU1_P2P2_DN<11>")
		)
		(pad "AM83" smd circle
			(at 30.914086 -12.397486 270)
			(size 0.4318 0.4318)
			(layers "F.Cu" "F.Mask" "F.Paste")
			(net "UPI_CPU0_CPU1_P2P2_DP<10>")
		)
		(pad "AM85" smd circle
			(at 32.541718 -12.397486 270)
			(size 0.4318 0.4318)
			(layers "F.Cu" "F.Mask" "F.Paste")
			(net "PVCCFA_EHV_FIVRA_CPU0")
		)
		(pad "AM87" smd circle
			(at 34.169604 -12.397486 270)
			(size 0.4318 0.4318)
			(layers "F.Cu" "F.Mask" "F.Paste")
			(net "P5E_CPU0_PE4_TX_DP<10>")
		)
		(pad "AM89" smd circle
			(at 35.797236 -12.397486 270)
			(size 0.4318 0.4318)
			(layers "F.Cu" "F.Mask" "F.Paste")
			(net "PVCCFA_EHV_FIVRA_CPU0")
		)
		(pad "AM91" smd oval
			(at 37.425122 -12.397486)
			(size 0.381 0.4826)
			(drill
				(offset 0 -0.0508)
			)
			(layers "F.Cu" "F.Mask" "F.Paste")
			(net "P5E_CPU0_PE4_RX_DN<10>")
		)
		(pad "AN1" smd oval
			(at -37.425122 -12.037314 180)
			(size 0.381 0.4826)
			(drill
				(offset 0 -0.0508)
			)
			(layers "F.Cu" "F.Mask" "F.Paste")
			(net "UPI_CPU0_CPU1_P0P1_DN<12>")
		)
		(pad "AN3" smd circle
			(at -35.797236 -12.037314 270)
			(size 0.4318 0.4318)
			(layers "F.Cu" "F.Mask" "F.Paste")
			(net "PVCCFA_EHV_CPU0")
		)
		(pad "AN5" smd circle
			(at -34.169604 -12.037314 270)
			(size 0.4318 0.4318)
			(layers "F.Cu" "F.Mask" "F.Paste")
			(net "UPI_CPU1_CPU0_P1P0_DP<11>")
		)
		(pad "AN7" smd circle
			(at -32.541718 -12.037314 270)
			(size 0.4318 0.4318)
			(layers "F.Cu" "F.Mask" "F.Paste")
			(net "PVCCFA_EHV_FIVRA_CPU0")
		)
		(pad "AN9" smd circle
			(at -30.914086 -12.037314 270)
			(size 0.4318 0.4318)
			(layers "F.Cu" "F.Mask" "F.Paste")
			(net "P5E_CPU0_PE0_RX_DP<11>")
		)
		(pad "AN11" smd circle
			(at -29.2862 -12.037314 270)
			(size 0.4318 0.4318)
			(layers "F.Cu" "F.Mask" "F.Paste")
			(net "PVCCFA_EHV_FIVRA_CPU0")
		)
		(pad "AN13" smd circle
			(at -27.658314 -12.037314 270)
			(size 0.4318 0.4318)
			(layers "F.Cu" "F.Mask" "F.Paste")
			(net "P5E_CPU0_PE0_TX_DN<10>")
		)
		(pad "AN15" smd circle
			(at -26.030682 -12.037314 270)
			(size 0.4318 0.4318)
			(layers "F.Cu" "F.Mask" "F.Paste")
			(net "PVCCFA_EHV_FIVRA_CPU0")
		)
		(pad "AN17" smd circle
			(at -24.402796 -12.037314 270)
			(size 0.4318 0.4318)
			(layers "F.Cu" "F.Mask" "F.Paste")
			(net "NC_CPU0_UPI0_APROBE<0>")
		)
		(pad "AN19" smd circle
			(at -22.77491 -12.037314 270)
			(size 0.4318 0.4318)
			(layers "F.Cu" "F.Mask" "F.Paste")
			(net "M_D_CPU0_SB_DQ<31>")
		)
		(pad "AN21" smd circle
			(at -21.147278 -12.037314 270)
			(size 0.4318 0.4318)
			(layers "F.Cu" "F.Mask" "F.Paste")
			(net "M_D_CPU0_SB_DQS_DN<8>")
		)
		(pad "AN23" smd circle
			(at -19.519392 -12.037314 270)
			(size 0.4318 0.4318)
			(layers "F.Cu" "F.Mask" "F.Paste")
			(net "M_D_CPU0_SB_DQ<26>")
		)
		(pad "AN25" smd circle
			(at -17.89176 -12.037314 270)
			(size 0.4318 0.4318)
			(layers "F.Cu" "F.Mask" "F.Paste")
			(net "M_D_CPU0_SB_DQ<15>")
		)
		(pad "AN27" smd circle
			(at -16.263874 -12.037314 270)
			(size 0.4318 0.4318)
			(layers "F.Cu" "F.Mask" "F.Paste")
			(net "M_D_CPU0_SB_DQS_DN<6>")
		)
		(pad "AN29" smd circle
			(at -14.635988 -12.037314 270)
			(size 0.4318 0.4318)
			(layers "F.Cu" "F.Mask" "F.Paste")
			(net "M_D_CPU0_SB_DQ<10>")
		)
		(pad "AN31" smd circle
			(at -13.008356 -12.037314 270)
			(size 0.4318 0.4318)
			(layers "F.Cu" "F.Mask" "F.Paste")
			(net "M_D_CPU0_SB_DQ<7>")
		)
		(pad "AN33" smd circle
			(at -11.380724 -12.037314 270)
			(size 0.4318 0.4318)
			(layers "F.Cu" "F.Mask" "F.Paste")
			(net "M_D_CPU0_SB_DQS_DN<5>")
		)
		(pad "AN35" smd circle
			(at -9.752838 -12.037314 270)
			(size 0.4318 0.4318)
			(layers "F.Cu" "F.Mask" "F.Paste")
			(net "M_D_CPU0_SB_DQ<2>")
		)
		(pad "AN37" smd circle
			(at -8.124952 -12.037314 270)
			(size 0.4318 0.4318)
			(layers "F.Cu" "F.Mask" "F.Paste")
			(net "M_D_CPU0_SB_CB<3>")
		)
		(pad "AN39" smd circle
			(at -6.49732 -12.037314 270)
			(size 0.4318 0.4318)
			(layers "F.Cu" "F.Mask" "F.Paste")
			(net "M_D_CPU0_SB_DQS_DP<4>")
		)
		(pad "AN41" smd circle
			(at -4.869434 -12.037314 270)
			(size 0.4318 0.4318)
			(layers "F.Cu" "F.Mask" "F.Paste")
			(net "M_D_CPU0_SB_CB<6>")
		)
		(pad "AN43" smd circle
			(at -3.241802 -12.037314 270)
			(size 0.4318 0.4318)
			(layers "F.Cu" "F.Mask" "F.Paste")
			(net "M_D_CPU0_SA_CA<6>")
		)
		(pad "AN45" smd circle
			(at -1.613916 -12.037314 270)
			(size 0.4318 0.4318)
			(layers "F.Cu" "F.Mask" "F.Paste")
			(net "M_D_CPU0_CLK_DN<1>")
		)
		(pad "AN48" smd circle
			(at 2.427732 -11.927332 270)
			(size 0.4318 0.4318)
			(layers "F.Cu" "F.Mask" "F.Paste")
			(net "M_B_CPU0_SB_RSP<0>")
		)
		(pad "AN50" smd circle
			(at 4.055618 -11.927332 270)
			(size 0.4318 0.4318)
			(layers "F.Cu" "F.Mask" "F.Paste")
			(net "M_D_CPU0_SA_CA<5>")
		)
		(pad "AN52" smd circle
			(at 5.68325 -11.927332 270)
			(size 0.4318 0.4318)
			(layers "F.Cu" "F.Mask" "F.Paste")
			(net "GND")
		)
		(pad "AN54" smd circle
			(at 7.311136 -11.927332 270)
			(size 0.4318 0.4318)
			(layers "F.Cu" "F.Mask" "F.Paste")
			(net "M_D_CPU0_SA_CS_N<2>")
		)
		(pad "AN56" smd circle
			(at 8.939022 -11.927332 270)
			(size 0.4318 0.4318)
			(layers "F.Cu" "F.Mask" "F.Paste")
			(net "M_D_CPU0_SA_CB<7>")
		)
		(pad "AN58" smd circle
			(at 10.566654 -11.927332 270)
			(size 0.4318 0.4318)
			(layers "F.Cu" "F.Mask" "F.Paste")
			(net "M_D_CPU0_SA_DQS_DN<9>")
		)
		(pad "AN60" smd circle
			(at 12.19454 -11.927332 270)
			(size 0.4318 0.4318)
			(layers "F.Cu" "F.Mask" "F.Paste")
			(net "M_D_CPU0_SA_CB<2>")
		)
		(pad "AN62" smd circle
			(at 13.822426 -11.927332 270)
			(size 0.4318 0.4318)
			(layers "F.Cu" "F.Mask" "F.Paste")
			(net "M_D_CPU0_SA_DQ<31>")
		)
		(pad "AN64" smd circle
			(at 15.450058 -11.927332 270)
			(size 0.4318 0.4318)
			(layers "F.Cu" "F.Mask" "F.Paste")
			(net "M_D_CPU0_SA_DQS_DN<8>")
		)
		(pad "AN66" smd circle
			(at 17.07769 -11.927332 270)
			(size 0.4318 0.4318)
			(layers "F.Cu" "F.Mask" "F.Paste")
			(net "M_D_CPU0_SA_DQ<26>")
		)
		(pad "AN68" smd circle
			(at 18.705576 -11.927332 270)
			(size 0.4318 0.4318)
			(layers "F.Cu" "F.Mask" "F.Paste")
			(net "M_D_CPU0_SA_DQ<23>")
		)
		(pad "AN70" smd circle
			(at 20.333462 -11.927332 270)
			(size 0.4318 0.4318)
			(layers "F.Cu" "F.Mask" "F.Paste")
			(net "M_D_CPU0_SA_DQS_DN<7>")
		)
		(pad "AN72" smd circle
			(at 21.961094 -11.927332 270)
			(size 0.4318 0.4318)
			(layers "F.Cu" "F.Mask" "F.Paste")
			(net "M_D_CPU0_SA_DQ<18>")
		)
		(pad "AN74" smd circle
			(at 23.58898 -11.927332 270)
			(size 0.4318 0.4318)
			(layers "F.Cu" "F.Mask" "F.Paste")
			(net "M_D_CPU0_SA_DQ<15>")
		)
		(pad "AN76" smd circle
			(at 25.216612 -11.927332 270)
			(size 0.4318 0.4318)
			(layers "F.Cu" "F.Mask" "F.Paste")
			(net "M_D_CPU0_SA_DQS_DN<6>")
		)
		(pad "AN78" smd circle
			(at 26.844498 -11.927332 270)
			(size 0.4318 0.4318)
			(layers "F.Cu" "F.Mask" "F.Paste")
			(net "M_D_CPU0_SA_DQ<10>")
		)
		(pad "AN80" smd circle
			(at 28.472384 -11.927332 270)
			(size 0.4318 0.4318)
			(layers "F.Cu" "F.Mask" "F.Paste")
			(net "PVCCFA_EHV_FIVRA_CPU0")
		)
		(pad "AN82" smd circle
			(at 30.100016 -11.927332 270)
			(size 0.4318 0.4318)
			(layers "F.Cu" "F.Mask" "F.Paste")
			(net "UPI_CPU0_CPU1_P2P2_DN<10>")
		)
		(pad "AN84" smd circle
			(at 31.727902 -11.927332 270)
			(size 0.4318 0.4318)
			(layers "F.Cu" "F.Mask" "F.Paste")
			(net "GND")
		)
		(pad "AN86" smd circle
			(at 33.355534 -11.927332 270)
			(size 0.4318 0.4318)
			(layers "F.Cu" "F.Mask" "F.Paste")
			(net "P5E_CPU0_PE4_TX_DP<11>")
		)
		(pad "AN88" smd circle
			(at 34.98342 -11.927332 270)
			(size 0.4318 0.4318)
			(layers "F.Cu" "F.Mask" "F.Paste")
			(net "GND")
		)
		(pad "AN90" smd circle
			(at 36.611306 -11.927332 270)
			(size 0.4318 0.4318)
			(layers "F.Cu" "F.Mask" "F.Paste")
			(net "P5E_CPU0_PE4_RX_DP<11>")
		)
		(pad "AP2" smd circle
			(at -36.611306 -11.567668 270)
			(size 0.4318 0.4318)
			(layers "F.Cu" "F.Mask" "F.Paste")
			(net "UPI_CPU0_CPU1_P0P1_DP<12>")
		)
		(pad "AP4" smd circle
			(at -34.98342 -11.567668 270)
			(size 0.4318 0.4318)
			(layers "F.Cu" "F.Mask" "F.Paste")
			(net "GND")
		)
		(pad "AP6" smd circle
			(at -33.355534 -11.567668 270)
			(size 0.4318 0.4318)
			(layers "F.Cu" "F.Mask" "F.Paste")
			(net "UPI_CPU1_CPU0_P1P0_DP<12>")
		)
		(pad "AP8" smd circle
			(at -31.727902 -11.567668 270)
			(size 0.4318 0.4318)
			(layers "F.Cu" "F.Mask" "F.Paste")
			(net "GND")
		)
		(pad "AP10" smd circle
			(at -30.100016 -11.567668 270)
			(size 0.4318 0.4318)
			(layers "F.Cu" "F.Mask" "F.Paste")
			(net "P5E_CPU0_PE0_RX_DN<12>")
		)
		(pad "AP12" smd circle
			(at -28.472384 -11.567668 270)
			(size 0.4318 0.4318)
			(layers "F.Cu" "F.Mask" "F.Paste")
			(net "GND")
		)
		(pad "AP14" smd circle
			(at -26.844498 -11.567668 270)
			(size 0.4318 0.4318)
			(layers "F.Cu" "F.Mask" "F.Paste")
			(net "P5E_CPU0_PE0_TX_DN<11>")
		)
		(pad "AP16" smd circle
			(at -25.216612 -11.567668 270)
			(size 0.4318 0.4318)
			(layers "F.Cu" "F.Mask" "F.Paste")
			(net "GND")
		)
		(pad "AP18" smd circle
			(at -23.58898 -11.567668 270)
			(size 0.4318 0.4318)
			(layers "F.Cu" "F.Mask" "F.Paste")
			(net "GND")
		)
		(pad "AP20" smd circle
			(at -21.961094 -11.567668 270)
			(size 0.4318 0.4318)
			(layers "F.Cu" "F.Mask" "F.Paste")
			(net "M_D_CPU0_SB_DQ<30>")
		)
		(pad "AP22" smd circle
			(at -20.333462 -11.567668 270)
			(size 0.4318 0.4318)
			(layers "F.Cu" "F.Mask" "F.Paste")
			(net "M_D_CPU0_SB_DQ<27>")
		)
		(pad "AP24" smd circle
			(at -18.705576 -11.567668 270)
			(size 0.4318 0.4318)
			(layers "F.Cu" "F.Mask" "F.Paste")
			(net "GND")
		)
		(pad "AP26" smd circle
			(at -17.07769 -11.567668 270)
			(size 0.4318 0.4318)
			(layers "F.Cu" "F.Mask" "F.Paste")
			(net "M_D_CPU0_SB_DQ<14>")
		)
		(pad "AP28" smd circle
			(at -15.450058 -11.567668 270)
			(size 0.4318 0.4318)
			(layers "F.Cu" "F.Mask" "F.Paste")
			(net "M_D_CPU0_SB_DQ<11>")
		)
		(pad "AP30" smd circle
			(at -13.822426 -11.567668 270)
			(size 0.4318 0.4318)
			(layers "F.Cu" "F.Mask" "F.Paste")
			(net "GND")
		)
		(pad "AP32" smd circle
			(at -12.19454 -11.567668 270)
			(size 0.4318 0.4318)
			(layers "F.Cu" "F.Mask" "F.Paste")
			(net "M_D_CPU0_SB_DQ<6>")
		)
		(pad "AP34" smd circle
			(at -10.566654 -11.567668 270)
			(size 0.4318 0.4318)
			(layers "F.Cu" "F.Mask" "F.Paste")
			(net "M_D_CPU0_SB_DQ<3>")
		)
		(pad "AP36" smd circle
			(at -8.939022 -11.567668 270)
			(size 0.4318 0.4318)
			(layers "F.Cu" "F.Mask" "F.Paste")
			(net "GND")
		)
		(pad "AP38" smd circle
			(at -7.311136 -11.567668 270)
			(size 0.4318 0.4318)
			(layers "F.Cu" "F.Mask" "F.Paste")
			(net "M_D_CPU0_SB_CB<2>")
		)
		(pad "AP40" smd circle
			(at -5.68325 -11.567668 270)
			(size 0.4318 0.4318)
			(layers "F.Cu" "F.Mask" "F.Paste")
			(net "M_D_CPU0_SB_CB<7>")
		)
		(pad "AP42" smd circle
			(at -4.055618 -11.567668 270)
			(size 0.4318 0.4318)
			(layers "F.Cu" "F.Mask" "F.Paste")
			(net "GND")
		)
		(pad "AP44" smd circle
			(at -2.427732 -11.567668 270)
			(size 0.4318 0.4318)
			(layers "F.Cu" "F.Mask" "F.Paste")
			(net "M_D_CPU0_SA_PAR")
		)
		(pad "AP47" smd circle
			(at 1.613916 -11.457686 270)
			(size 0.4318 0.4318)
			(layers "F.Cu" "F.Mask" "F.Paste")
			(net "M_B_CPU0_SB_RSP<1>")
		)
		(pad "AP49" smd circle
			(at 3.241802 -11.457686 270)
			(size 0.4318 0.4318)
			(layers "F.Cu" "F.Mask" "F.Paste")
			(net "GND")
		)
		(pad "AP51" smd circle
			(at 4.869434 -11.457686 270)
			(size 0.4318 0.4318)
			(layers "F.Cu" "F.Mask" "F.Paste")
			(net "M_D_CPU0_SA_CA<3>")
		)
		(pad "AP53" smd circle
			(at 6.49732 -11.457686 270)
			(size 0.4318 0.4318)
			(layers "F.Cu" "F.Mask" "F.Paste")
			(net "M_D_CPU0_SA_CS_N<3>")
		)
		(pad "AP55" smd circle
			(at 8.124952 -11.457686 270)
			(size 0.4318 0.4318)
			(layers "F.Cu" "F.Mask" "F.Paste")
			(net "GND")
		)
		(pad "AP57" smd circle
			(at 9.752838 -11.457686 270)
			(size 0.4318 0.4318)
			(layers "F.Cu" "F.Mask" "F.Paste")
			(net "M_D_CPU0_SA_CB<6>")
		)
		(pad "AP59" smd circle
			(at 11.380724 -11.457686 270)
			(size 0.4318 0.4318)
			(layers "F.Cu" "F.Mask" "F.Paste")
			(net "M_D_CPU0_SA_CB<3>")
		)
	)
)
